# GPS_MODULE_ZED-F9T-00B_BOM_sma_ver.xlsx — GPS_MODULE_ZED-F9T-00B_BOM (bom)
| Designator | Quantity | Manufacturer | Manufacturer 1 | Manufacturer Part Number | Manufacturer Part Number 1 | Supplier 1 | Supplier Part Number 1 | Description | Case/Package |
| C1, C2, C3, C4, C5 | 5 | Murata |  | GRM155R61E105KA12D |  | Digikey | 490-10017-1-ND | CAP, CER, X5R, 1UF, 10%, 25V, 0402, 0.55MM T | 0402 (1005 Metric) |
| C6, C7, C8, C9 | 4 |  | Taiyo Yuden |  | UMK105BJ104KV-F | Farnell | 2779049 | None | 0402 |
| C10 | 1 |  | Murata |  | GRM033R71C103KE14D | Farnell | 2990695 | Chip Multilayer Ceramic Capacitors for General Purpose, 0201, 10000pF, X7R, 15%, 10%, 16V |  |
| D1 | 1 | Littelfuse Inc. | Littelfuse | PESD0402-140 | PESD0402-140 | Future Electronics | 1128358 | TVS DIODE 14V 40V 0402 |  |
| DS1, DS2, DS3 | 3 | Lumex Opto/Components Inc. |  | SML-LXFM0603SUGCTR |  | Digikey | 67-2320-1-ND | LED, GREEN, 574NM, 20MA, 20MCD MIN, 2.5VF MAX, 0603, 1.10MM T | 0603 (1608 Metric) |
| J1 | 1 | Sullins | Sullins | NRPN042MAMS-RC | NRPN042MAMS-RC | Digi-Key | S6009-04-ND | Dual Row 8 Position 2 mm Pitch Surface Mount Header |  |
| J2 | 1 | Bel Cinch | Bel Cinch | 131-3711-301 | 131-3711-301 | Digi-Key | J10507-ND | Rf Coaxial Board Mount Connector | SMA |
| L1 | 1 |  | Murata |  | LQG15HS47NJ02D | Future Electronics | 1091743 | Multilayer type RF Inductor 47nH ±5% 0.72Ω 300mA 0402 | 0402 |
| Q1 | 1 | onsemi |  | NTR2101PT1G |  | Digikey | NTR2101PT1GOSCT-ND | MOSFET, P-CH, 8VDS, 3.7A ID, 0.052 OHM RDS(ON)@4.5VGS/3.5A, SOT-23-3 | TO-236-3, SC-59, SOT-23-3 |
| R1, R2, R3, R10, R13, R14 | 6 |  | Stackpole Electronics |  | RMCF0402FT1K00 | Future Electronics | 6297634 | 1kΩ ±1% 0.063W 0402 Thick Film Chip Resistor AEC-Q200 compliant | 0402 |
| R4, R7, R8 | 3 |  | Stackpole Electronics |  | RMCF0402FT10K0 | Future Electronics | 1731694 | 10kΩ ±1% 0.063W 0402 Thick Film Chip Resistor AEC-Q200 compliant | 0402 |
| R9, R11 | 2 |  | Stackpole Electronics |  | RMCF0402FT100K | Future Electronics | 8519472 | 100kΩ ±1% 0.063W 0402 Thick Film Chip Resistor AEC-Q200 compliant | 0402 |
| R12 | 1 | Vishay |  | RCP0603W25R0GEB |  | Digikey | 541-2654-1-ND | RES, 25 OHM, 2%, 1.5W, 150PPM/C, 0603 | 0603 (1608 Metric) |
| U1 | 1 | u-blox | u-blox | ZED-F9T-00B | ZED-F9T-00B | Digi-Key | 672-1197-1-ND | Multi-band GNSS Receiver with Nanosecond-level Timing Accuracy | SMD/SMT |
| U2, U3 | 2 | Texas Instruments | Texas Instruments |  | SN74LVC3G07DCUR | Farnell | 2460000 | Triple Buffer/Driver With Open-Drain Output, DCU0008A, LARGE T&R |  |
| U4 | 1 | Texas Instruments | TI National Semiconductor |  | LPV511MGX/NOPB | Digi-Key | 296-44295-1-ND | micropower Rail-to-Rail Input and Output Operational Amplifier, 5-pin SC-70, Pb-Free |  |
